(kicad_pcb
	(version 20241229)
	(generator "pcbnew")
	(generator_version "9.0")
	(general
		(thickness 1.711)
		(legacy_teardrops no)
	)
	(paper "A4")
	(title_block
		(title "Antmicro Baseboard for Jetson AGX Thor")
		(date "2026-02-18")
		(rev "1.1.0")
		(company "Antmicro Ltd")
		(comment 1 "www.antmicro.com")
		(comment 9 "footprints 650-654 of 1170")
	)
	(layers
		(0 "F.Cu" signal)
		(4 "In1.Cu" signal)
		(6 "In2.Cu" signal)
		(8 "In3.Cu" signal)
		(10 "In4.Cu" jumper)
		(12 "In5.Cu" signal)
		(14 "In6.Cu" signal)
		(16 "In7.Cu" signal)
		(18 "In8.Cu" signal)
		(2 "B.Cu" signal)
		(9 "F.Adhes" user "F.Adhesive")
		(11 "B.Adhes" user "B.Adhesive")
		(13 "F.Paste" user)
		(15 "B.Paste" user)
		(5 "F.SilkS" user "F.Silkscreen")
		(7 "B.SilkS" user "B.Silkscreen")
		(1 "F.Mask" user)
		(3 "B.Mask" user)
		(17 "Dwgs.User" user "User.Drawings")
		(19 "Cmts.User" user "User.Comments")
		(21 "Eco1.User" user "User.Eco1")
		(23 "Eco2.User" user "User.Eco2")
		(25 "Edge.Cuts" user)
		(27 "Margin" user)
		(31 "F.CrtYd" user "F.Courtyard")
		(29 "B.CrtYd" user "B.Courtyard")
		(35 "F.Fab" user)
		(33 "B.Fab" user)
	)
	(footprint "antmicro-footprints:R_0402_1005Metric"
		(layer "B.Cu")
		(at 203.4 101.800001 180)
		(descr "Resistor SMD 0402")
		(tags "resistor SMD 0402")
		(property "Reference" "R252"
			(at -0.8 0.600001 0)
			(layer "B.SilkS")
			(effects
				(font
					(size 0.7 0.7)
					(thickness 0.15)
				)
				(justify left bottom mirror)
			)
		)
		(property "Value" "R_0R_0402"
			(at -1.011843 -1.772046 0)
			(layer "B.Fab")
			(effects
				(font
					(size 0.7 0.7)
					(thickness 0.15)
				)
				(justify left bottom mirror)
			)
		)
		(property "Datasheet" "https://industrial.panasonic.com/cdbs/www-data/pdf/RDA0000/AOA0000C301.pdf"
			(at 0 0 0)
			(layer "B.Fab")
			(hide yes)
			(effects
				(font
					(size 1.27 1.27)
					(thickness 0.15)
				)
				(justify mirror)
			)
		)
		(property "Description" "SMD Chip Resistor, Jumper, 0 ohm, 100 mW, 0402 [1005 Metric], Thick Film, General Purpose"
			(at 0 0 0)
			(layer "B.Fab")
			(hide yes)
			(effects
				(font
					(size 1.27 1.27)
					(thickness 0.15)
				)
				(justify mirror)
			)
		)
		(property "Manufacturer" "Panasonic"
			(at 0 0 0)
			(unlocked yes)
			(layer "B.Fab")
			(hide yes)
			(effects
				(font
					(size 1 1)
					(thickness 0.15)
				)
				(justify mirror)
			)
		)
		(property "MPN" "ERJ2GE0R00X"
			(at 0 0 0)
			(unlocked yes)
			(layer "B.Fab")
			(hide yes)
			(effects
				(font
					(size 1 1)
					(thickness 0.15)
				)
				(justify mirror)
			)
		)
		(property "Val" "0R"
			(at 0 0 0)
			(unlocked yes)
			(layer "B.Fab")
			(hide yes)
			(effects
				(font
					(size 1 1)
					(thickness 0.15)
				)
				(justify mirror)
			)
		)
		(property "License" "Apache-2.0"
			(at 0 0 0)
			(unlocked yes)
			(layer "B.Fab")
			(hide yes)
			(effects
				(font
					(size 1 1)
					(thickness 0.15)
				)
				(justify mirror)
			)
		)
		(property "Author" "Antmicro"
			(at 0 0 0)
			(unlocked yes)
			(layer "B.Fab")
			(hide yes)
			(effects
				(font
					(size 1 1)
					(thickness 0.15)
				)
				(justify mirror)
			)
		)
		(property "Tolerance" "~"
			(at 0 0 0)
			(unlocked yes)
			(layer "B.Fab")
			(hide yes)
			(effects
				(font
					(size 1 1)
					(thickness 0.15)
				)
				(justify mirror)
			)
		)
		(property "Current" "1A"
			(at 0 0 0)
			(unlocked yes)
			(layer "B.Fab")
			(hide yes)
			(effects
				(font
					(size 1 1)
					(thickness 0.15)
				)
				(justify mirror)
			)
		)
		(sheetname "/Recovery USB/")
		(sheetfile "recovery_usb.kicad_sch")
		(attr smd exclude_from_pos_files exclude_from_bom dnp)
		(fp_poly
			(pts
				(xy -0.925 0.47) (xy 0.925 0.47) (xy 0.925 -0.47) (xy -0.925 -0.47)
			)
			(stroke
				(width 0.05)
				(type default)
			)
			(fill no)
			(layer "B.CrtYd")
		)
		(fp_poly
			(pts
				(xy -0.5 0.25) (xy 0.5 0.25) (xy 0.5 -0.25) (xy -0.5 -0.25)
			)
			(stroke
				(width 0.15)
				(type solid)
			)
			(fill no)
			(layer "B.Fab")
		)
		(fp_text user "Author: Antmicro"
			(at -0.95 -4.169 0)
			(layer "B.Fab")
			(effects
				(font
					(size 0.7 0.7)
					(thickness 0.15)
				)
				(justify left bottom mirror)
			)
		)
		(fp_text user "License: Apache-2.0"
			(at -0.949999 -5.169 0)
			(layer "B.Fab")
			(effects
				(font
					(size 0.7 0.7)
					(thickness 0.15)
				)
				(justify left bottom mirror)
			)
		)
		(fp_text user "${REFERENCE}"
			(at -0.95 -3.168 0)
			(layer "B.Fab")
			(effects
				(font
					(size 0.7 0.7)
					(thickness 0.15)
				)
				(justify left bottom mirror)
			)
		)
		(pad "1" smd roundrect
			(at -0.48 0 180)
			(size 0.59 0.64)
			(layers "B.Cu" "B.Mask" "B.Paste")
			(roundrect_rratio 0.25)
			(net 1011 "/Recovery USB/USBC2_ADDR")
			(pintype "passive")
		)
		(pad "2" smd roundrect
			(at 0.48 0 180)
			(size 0.59 0.64)
			(layers "B.Cu" "B.Mask" "B.Paste")
			(roundrect_rratio 0.25)
			(net 5 "+5V")
			(pintype "passive")
		)
	)
	(footprint "antmicro-footprints:R_0402_1005Metric"
		(layer "B.Cu")
		(at 178.3 66.3)
		(descr "Resistor SMD 0402")
		(tags "resistor SMD 0402")
		(property "Reference" "R217"
			(at 1.1 -0.5 180)
			(layer "B.SilkS")
			(effects
				(font
					(size 0.7 0.7)
					(thickness 0.15)
				)
				(justify left bottom mirror)
			)
		)
		(property "Value" "R_0R_0402"
			(at -1.011843 -1.772046 180)
			(layer "B.Fab")
			(effects
				(font
					(size 0.7 0.7)
					(thickness 0.15)
				)
				(justify left bottom mirror)
			)
		)
		(property "Datasheet" "https://industrial.panasonic.com/cdbs/www-data/pdf/RDA0000/AOA0000C301.pdf"
			(at 0 0 180)
			(layer "B.Fab")
			(hide yes)
			(effects
				(font
					(size 1.27 1.27)
					(thickness 0.15)
				)
				(justify mirror)
			)
		)
		(property "Description" "SMD Chip Resistor, Jumper, 0 ohm, 100 mW, 0402 [1005 Metric], Thick Film, General Purpose"
			(at 0 0 180)
			(layer "B.Fab")
			(hide yes)
			(effects
				(font
					(size 1.27 1.27)
					(thickness 0.15)
				)
				(justify mirror)
			)
		)
		(property "MPN" "ERJ2GE0R00X"
			(at 0 0 180)
			(unlocked yes)
			(layer "B.Fab")
			(hide yes)
			(effects
				(font
					(size 1 1)
					(thickness 0.15)
				)
				(justify mirror)
			)
		)
		(property "Manufacturer" "Panasonic"
			(at 0 0 180)
			(unlocked yes)
			(layer "B.Fab")
			(hide yes)
			(effects
				(font
					(size 1 1)
					(thickness 0.15)
				)
				(justify mirror)
			)
		)
		(property "License" "Apache-2.0"
			(at 0 0 180)
			(unlocked yes)
			(layer "B.Fab")
			(hide yes)
			(effects
				(font
					(size 1 1)
					(thickness 0.15)
				)
				(justify mirror)
			)
		)
		(property "Author" "Antmicro"
			(at 0 0 180)
			(unlocked yes)
			(layer "B.Fab")
			(hide yes)
			(effects
				(font
					(size 1 1)
					(thickness 0.15)
				)
				(justify mirror)
			)
		)
		(property "Val" "0R"
			(at 0 0 180)
			(unlocked yes)
			(layer "B.Fab")
			(hide yes)
			(effects
				(font
					(size 1 1)
					(thickness 0.15)
				)
				(justify mirror)
			)
		)
		(property "Tolerance" "~"
			(at 0 0 180)
			(unlocked yes)
			(layer "B.Fab")
			(hide yes)
			(effects
				(font
					(size 1 1)
					(thickness 0.15)
				)
				(justify mirror)
			)
		)
		(property "Current" "1A"
			(at 0 0 180)
			(unlocked yes)
			(layer "B.Fab")
			(hide yes)
			(effects
				(font
					(size 1 1)
					(thickness 0.15)
				)
				(justify mirror)
			)
		)
		(component_classes
			(class "DCDC_20V")
		)
		(sheetname "/DCDC/")
		(sheetfile "dcdc.kicad_sch")
		(attr smd)
		(fp_poly
			(pts
				(xy -0.925 0.47) (xy 0.925 0.47) (xy 0.925 -0.47) (xy -0.925 -0.47)
			)
			(stroke
				(width 0.05)
				(type default)
			)
			(fill no)
			(layer "B.CrtYd")
		)
		(fp_poly
			(pts
				(xy -0.5 0.25) (xy 0.5 0.25) (xy 0.5 -0.25) (xy -0.5 -0.25)
			)
			(stroke
				(width 0.15)
				(type solid)
			)
			(fill no)
			(layer "B.Fab")
		)
		(fp_text user "License: Apache-2.0"
			(at -0.949999 -5.169 180)
			(layer "B.Fab")
			(effects
				(font
					(size 0.7 0.7)
					(thickness 0.15)
				)
				(justify left bottom mirror)
			)
		)
		(fp_text user "${REFERENCE}"
			(at -0.95 -3.168 180)
			(layer "B.Fab")
			(effects
				(font
					(size 0.7 0.7)
					(thickness 0.15)
				)
				(justify left bottom mirror)
			)
		)
		(fp_text user "Author: Antmicro"
			(at -0.95 -4.169 180)
			(layer "B.Fab")
			(effects
				(font
					(size 0.7 0.7)
					(thickness 0.15)
				)
				(justify left bottom mirror)
			)
		)
		(pad "1" smd roundrect
			(at -0.48 0)
			(size 0.59 0.64)
			(layers "B.Cu" "B.Mask" "B.Paste")
			(roundrect_rratio 0.25)
			(net 1293 "/DCDC/CARRIER_PWR_ON")
			(pintype "passive")
		)
		(pad "2" smd roundrect
			(at 0.48 0)
			(size 0.59 0.64)
			(layers "B.Cu" "B.Mask" "B.Paste")
			(roundrect_rratio 0.25)
			(net 1211 "/DCDC/20V_EN")
			(pintype "passive")
		)
	)
	(footprint "antmicro-footprints:R_0402_1005Metric"
		(layer "B.Cu")
		(at 237.68 94.4 180)
		(descr "Resistor SMD 0402")
		(tags "resistor SMD 0402")
		(property "Reference" "R143"
			(at -2.12 -1.4 0)
			(layer "B.SilkS")
			(effects
				(font
					(size 0.7 0.7)
					(thickness 0.15)
				)
				(justify left bottom mirror)
			)
		)
		(property "Value" "R_0R_0402"
			(at -1.011843 -1.772046 0)
			(layer "B.Fab")
			(effects
				(font
					(size 0.7 0.7)
					(thickness 0.15)
				)
				(justify left bottom mirror)
			)
		)
		(property "Datasheet" "https://industrial.panasonic.com/cdbs/www-data/pdf/RDA0000/AOA0000C301.pdf"
			(at 0 0 0)
			(layer "B.Fab")
			(hide yes)
			(effects
				(font
					(size 1.27 1.27)
					(thickness 0.15)
				)
				(justify mirror)
			)
		)
		(property "Description" "SMD Chip Resistor, Jumper, 0 ohm, 100 mW, 0402 [1005 Metric], Thick Film, General Purpose"
			(at 0 0 0)
			(layer "B.Fab")
			(hide yes)
			(effects
				(font
					(size 1.27 1.27)
					(thickness 0.15)
				)
				(justify mirror)
			)
		)
		(property "Manufacturer" "Panasonic"
			(at 0 0 0)
			(unlocked yes)
			(layer "B.Fab")
			(hide yes)
			(effects
				(font
					(size 1 1)
					(thickness 0.15)
				)
				(justify mirror)
			)
		)
		(property "MPN" "ERJ2GE0R00X"
			(at 0 0 0)
			(unlocked yes)
			(layer "B.Fab")
			(hide yes)
			(effects
				(font
					(size 1 1)
					(thickness 0.15)
				)
				(justify mirror)
			)
		)
		(property "Val" "0R"
			(at 0 0 0)
			(unlocked yes)
			(layer "B.Fab")
			(hide yes)
			(effects
				(font
					(size 1 1)
					(thickness 0.15)
				)
				(justify mirror)
			)
		)
		(property "License" "Apache-2.0"
			(at 0 0 0)
			(unlocked yes)
			(layer "B.Fab")
			(hide yes)
			(effects
				(font
					(size 1 1)
					(thickness 0.15)
				)
				(justify mirror)
			)
		)
		(property "Author" "Antmicro"
			(at 0 0 0)
			(unlocked yes)
			(layer "B.Fab")
			(hide yes)
			(effects
				(font
					(size 1 1)
					(thickness 0.15)
				)
				(justify mirror)
			)
		)
		(property "Tolerance" "~"
			(at 0 0 0)
			(unlocked yes)
			(layer "B.Fab")
			(hide yes)
			(effects
				(font
					(size 1 1)
					(thickness 0.15)
				)
				(justify mirror)
			)
		)
		(property "Current" "1A"
			(at 0 0 0)
			(unlocked yes)
			(layer "B.Fab")
			(hide yes)
			(effects
				(font
					(size 1 1)
					(thickness 0.15)
				)
				(justify mirror)
			)
		)
		(sheetname "/USB DP Alt mode/")
		(sheetfile "usb_dp.kicad_sch")
		(attr smd)
		(fp_poly
			(pts
				(xy -0.925 0.47) (xy -0.925 -0.47) (xy 0.925 -0.47) (xy 0.925 0.47)
			)
			(stroke
				(width 0.05)
				(type default)
			)
			(fill no)
			(layer "B.CrtYd")
		)
		(fp_poly
			(pts
				(xy -0.5 0.25) (xy -0.5 -0.25) (xy 0.5 -0.25) (xy 0.5 0.25)
			)
			(stroke
				(width 0.15)
				(type solid)
			)
			(fill no)
			(layer "B.Fab")
		)
		(fp_text user "${REFERENCE}"
			(at -0.95 -3.168 0)
			(layer "B.Fab")
			(effects
				(font
					(size 0.7 0.7)
					(thickness 0.15)
				)
				(justify left bottom mirror)
			)
		)
		(fp_text user "Author: Antmicro"
			(at -0.95 -4.169 0)
			(layer "B.Fab")
			(effects
				(font
					(size 0.7 0.7)
					(thickness 0.15)
				)
				(justify left bottom mirror)
			)
		)
		(fp_text user "License: Apache-2.0"
			(at -0.949999 -5.169 0)
			(layer "B.Fab")
			(effects
				(font
					(size 0.7 0.7)
					(thickness 0.15)
				)
				(justify left bottom mirror)
			)
		)
		(pad "1" smd roundrect
			(at -0.48 0 180)
			(size 0.59 0.64)
			(layers "B.Cu" "B.Mask" "B.Paste")
			(roundrect_rratio 0.25)
			(net 970 "/USB DP Alt mode/USBC1_5V_PEN")
			(pintype "passive")
		)
		(pad "2" smd roundrect
			(at 0.48 0 180)
			(size 0.59 0.64)
			(layers "B.Cu" "B.Mask" "B.Paste")
			(roundrect_rratio 0.25)
			(net 971 "Net-(U35-EN)")
			(pintype "passive")
		)
	)
	(footprint "antmicro-footprints:C_0603_1608Metric_EIA"
		(layer "B.Cu")
		(at 124.6 112)
		(descr "Capacitor SMD 0603, IPC-7351 Density Level A")
		(tags "Capacitor 0603")
		(property "Reference" "C192"
			(at 1.2 1.2 0)
			(layer "B.SilkS")
			(effects
				(font
					(size 0.7 0.7)
					(thickness 0.15)
				)
				(justify right top mirror)
			)
		)
		(property "Value" "C_22u_16V_0603"
			(at -1.42757 -1.770288 0)
			(layer "B.Fab")
			(effects
				(font
					(size 0.7 0.7)
					(thickness 0.15)
				)
				(justify right top mirror)
			)
		)
		(property "Datasheet" "https://product.samsungsem.com/mlcc/CL10A226MO7JZN.do"
			(at 0 0 0)
			(layer "B.Fab")
			(hide yes)
			(effects
				(font
					(size 1.27 1.27)
					(thickness 0.15)
				)
				(justify mirror)
			)
		)
		(property "Description" "SMD Multilayer Ceramic Capacitor"
			(at 0 0 0)
			(layer "B.Fab")
			(hide yes)
			(effects
				(font
					(size 1.27 1.27)
					(thickness 0.15)
				)
				(justify mirror)
			)
		)
		(property "Manufacturer" "Samsung Electro-Mechanics"
			(at 0 0 0)
			(unlocked yes)
			(layer "B.Fab")
			(hide yes)
			(effects
				(font
					(size 1 1)
					(thickness 0.15)
				)
				(justify mirror)
			)
		)
		(property "MPN" "CL10A226MO7JZNC"
			(at 0 0 0)
			(unlocked yes)
			(layer "B.Fab")
			(hide yes)
			(effects
				(font
					(size 1 1)
					(thickness 0.15)
				)
				(justify mirror)
			)
		)
		(property "Val" "22u"
			(at 0 0 0)
			(unlocked yes)
			(layer "B.Fab")
			(hide yes)
			(effects
				(font
					(size 1 1)
					(thickness 0.15)
				)
				(justify mirror)
			)
		)
		(property "License" "Apache-2.0"
			(at 0 0 0)
			(unlocked yes)
			(layer "B.Fab")
			(hide yes)
			(effects
				(font
					(size 1 1)
					(thickness 0.15)
				)
				(justify mirror)
			)
		)
		(property "Author" "Antmicro"
			(at 0 0 0)
			(unlocked yes)
			(layer "B.Fab")
			(hide yes)
			(effects
				(font
					(size 1 1)
					(thickness 0.15)
				)
				(justify mirror)
			)
		)
		(property "Voltage" "16V"
			(at 0 0 0)
			(unlocked yes)
			(layer "B.Fab")
			(hide yes)
			(effects
				(font
					(size 1 1)
					(thickness 0.15)
				)
				(justify mirror)
			)
		)
		(property "Dielectric" "template_dielectric"
			(at 0 0 0)
			(unlocked yes)
			(layer "B.Fab")
			(hide yes)
			(effects
				(font
					(size 1 1)
					(thickness 0.15)
				)
				(justify mirror)
			)
		)
		(sheetname "/M.2/")
		(sheetfile "m2.kicad_sch")
		(attr smd)
		(fp_line
			(start -0.15 -0.55)
			(end 0.15 -0.55)
			(stroke
				(width 0.15)
				(type solid)
			)
			(layer "B.SilkS")
		)
		(fp_line
			(start -0.15 0.55)
			(end 0.15 0.55)
			(stroke
				(width 0.15)
				(type solid)
			)
			(layer "B.SilkS")
		)
		(fp_poly
			(pts
				(xy -1.25 0.65) (xy -1.25 -0.65) (xy 1.25 -0.65) (xy 1.25 0.65)
			)
			(stroke
				(width 0.05)
				(type solid)
			)
			(fill no)
			(layer "B.CrtYd")
		)
		(fp_poly
			(pts
				(xy -0.799999 0.45) (xy -0.799999 -0.45) (xy 0.799999 -0.45) (xy 0.799999 0.45)
			)
			(stroke
				(width 0.15)
				(type solid)
			)
			(fill no)
			(layer "B.Fab")
		)
		(fp_text user "${REFERENCE}"
			(at -1.682001 -3.895 0)
			(layer "B.Fab")
			(effects
				(font
					(size 0.7 0.7)
					(thickness 0.15)
				)
				(justify right top mirror)
			)
		)
		(fp_text user "License: Apache-2.0"
			(at -1.682 -5.895 0)
			(layer "B.Fab")
			(effects
				(font
					(size 0.7 0.7)
					(thickness 0.15)
				)
				(justify right top mirror)
			)
		)
		(fp_text user "Author: Antmicro"
			(at -1.682 -4.894 0)
			(layer "B.Fab")
			(effects
				(font
					(size 0.7 0.7)
					(thickness 0.15)
				)
				(justify right top mirror)
			)
		)
		(pad "1" smd roundrect
			(at -0.7 0)
			(size 0.8 1.1)
			(layers "B.Cu" "B.Mask" "B.Paste")
			(roundrect_rratio 0.2)
			(net 14 "/M.2/3V3_M2")
			(pintype "passive")
		)
		(pad "2" smd roundrect
			(at 0.7 0)
			(size 0.8 1.1)
			(layers "B.Cu" "B.Mask" "B.Paste")
			(roundrect_rratio 0.2)
			(net 1 "GND")
			(pintype "passive")
		)
	)
	(footprint "antmicro-footprints:R_0402_1005Metric"
		(layer "B.Cu")
		(at 238.2 106.8)
		(descr "Resistor SMD 0402")
		(tags "resistor SMD 0402")
		(property "Reference" "R265"
			(at -1.1 1.6 0)
			(layer "B.SilkS")
			(effects
				(font
					(size 0.7 0.7)
					(thickness 0.15)
				)
				(justify right top mirror)
			)
		)
		(property "Value" "R_1k_0402"
			(at -1.011843 -1.772046 0)
			(layer "B.Fab")
			(effects
				(font
					(size 0.7 0.7)
					(thickness 0.15)
				)
				(justify right top mirror)
			)
		)
		(property "Datasheet" "https://www.bourns.com/docs/product-datasheets/cr.pdf"
			(at 0 0 0)
			(layer "B.Fab")
			(hide yes)
			(effects
				(font
					(size 1.27 1.27)
					(thickness 0.15)
				)
				(justify mirror)
			)
		)
		(property "Description" "SMD Chip Resistor, 1 kohm, ± 1%, 63 mW, 0402 [1005 Metric], Thick Film, General Purpose"
			(at 0 0 0)
			(layer "B.Fab")
			(hide yes)
			(effects
				(font
					(size 1.27 1.27)
					(thickness 0.15)
				)
				(justify mirror)
			)
		)
		(property "Manufacturer" "Bourns"
			(at 0 0 180)
			(unlocked yes)
			(layer "B.Fab")
			(hide yes)
			(effects
				(font
					(size 1 1)
					(thickness 0.15)
				)
				(justify mirror)
			)
		)
		(property "MPN" "CR0402-FX-1001GLF"
			(at 0 0 180)
			(unlocked yes)
			(layer "B.Fab")
			(hide yes)
			(effects
				(font
					(size 1 1)
					(thickness 0.15)
				)
				(justify mirror)
			)
		)
		(property "Val" "1k"
			(at 0 0 180)
			(unlocked yes)
			(layer "B.Fab")
			(hide yes)
			(effects
				(font
					(size 1 1)
					(thickness 0.15)
				)
				(justify mirror)
			)
		)
		(property "License" "Apache-2.0"
			(at 0 0 180)
			(unlocked yes)
			(layer "B.Fab")
			(hide yes)
			(effects
				(font
					(size 1 1)
					(thickness 0.15)
				)
				(justify mirror)
			)
		)
		(property "Author" "Antmicro"
			(at 0 0 180)
			(unlocked yes)
			(layer "B.Fab")
			(hide yes)
			(effects
				(font
					(size 1 1)
					(thickness 0.15)
				)
				(justify mirror)
			)
		)
		(property "Tolerance" "1%"
			(at 0 0 180)
			(unlocked yes)
			(layer "B.Fab")
			(hide yes)
			(effects
				(font
					(size 1 1)
					(thickness 0.15)
				)
				(justify mirror)
			)
		)
		(sheetname "/Recovery USB/")
		(sheetfile "recovery_usb.kicad_sch")
		(attr smd)
		(fp_poly
			(pts
				(xy -0.925 0.47) (xy -0.925 -0.47) (xy 0.925 -0.47) (xy 0.925 0.47)
			)
			(stroke
				(width 0.05)
				(type default)
			)
			(fill no)
			(layer "B.CrtYd")
		)
		(fp_poly
			(pts
				(xy -0.5 0.25) (xy -0.5 -0.25) (xy 0.5 -0.25) (xy 0.5 0.25)
			)
			(stroke
				(width 0.15)
				(type solid)
			)
			(fill no)
			(layer "B.Fab")
		)
		(fp_text user "${REFERENCE}"
			(at -0.95 -3.168 0)
			(layer "B.Fab")
			(effects
				(font
					(size 0.7 0.7)
					(thickness 0.15)
				)
				(justify right top mirror)
			)
		)
		(fp_text user "Author: Antmicro"
			(at -0.95 -4.169 0)
			(layer "B.Fab")
			(effects
				(font
					(size 0.7 0.7)
					(thickness 0.15)
				)
				(justify right top mirror)
			)
		)
		(fp_text user "License: Apache-2.0"
			(at -0.949999 -5.169 0)
			(layer "B.Fab")
			(effects
				(font
					(size 0.7 0.7)
					(thickness 0.15)
				)
				(justify right top mirror)
			)
		)
		(pad "1" smd roundrect
			(at -0.48 0)
			(size 0.59 0.64)
			(layers "B.Cu" "B.Mask" "B.Paste")
			(roundrect_rratio 0.25)
			(net 1245 "Net-(R265-Pad1)")
			(pintype "passive")
		)
		(pad "2" smd roundrect
			(at 0.48 0)
			(size 0.59 0.64)
			(layers "B.Cu" "B.Mask" "B.Paste")
			(roundrect_rratio 0.25)
			(net 2 "+3V3")
			(pintype "passive")
		)
	)
)
